# BASEBOARD_FAB2 (Tioga Pass) — schematic netlist excerpt (pin names and nets, part order shuffled) for the footprints in the layout excerpt that follows; sources: Cadence DE-HDL packaged netlist, KiCad conversion of Wiwynn_Tioga_Pass_MB.brd

C9M4  CAP  10UF 16V 10% X6S  pkg 0805  page 161 : A = P12V_FAN ; B = GND
C1G17  CAP  22UF 4V 20% X6S  pkg 0805LF  page 224 : A = PVDDQ_GHJ ; B = GND
C1E17  CAP_A  0.1UF 16V 10% X7R  pkg 0402V  page 195 : A = P12V_PSU ; B = GND

(kicad_pcb
	(version 20260206)
	(generator "pcbnew")
	(generator_version "10.0")
	(general
		(thickness 1.6)
		(legacy_teardrops no)
	)
	(paper "A4")
	(title_block
		(title "Wiwynn_Tioga_Pass_MB.brd")
		(comment 1 "Tioga Pass / footprints 395-397 of 4770")
	)
	(layers
		(0 "F.Cu" signal "TOP")
		(4 "In1.Cu" signal "L2GND")
		(6 "In2.Cu" signal "L3")
		(8 "In3.Cu" signal "L4GND")
		(10 "In4.Cu" signal "L5")
		(12 "In5.Cu" signal "L6GND")
		(14 "In6.Cu" signal "L7VCC")
		(16 "In7.Cu" signal "L8VCC")
		(18 "In8.Cu" signal "L9GND")
		(20 "In9.Cu" signal "L10")
		(22 "In10.Cu" signal "L11GND")
		(24 "In11.Cu" signal "L12")
		(26 "In12.Cu" signal "L13GND")
		(2 "B.Cu" signal "BOTTOM")
		(9 "F.Adhes" user "F.Adhesive")
		(11 "B.Adhes" user "B.Adhesive")
		(13 "F.Paste" user "Package Geometry/Pastemask Top")
		(15 "B.Paste" user "Package Geometry/Pastemask Bottom")
		(5 "F.SilkS" user "Ref Des/Silkscreen Top")
		(7 "B.SilkS" user "Ref Des/Silkscreen Bottom")
		(1 "F.Mask" user "Board Geometry/Soldermask Top")
		(3 "B.Mask" user "Board Geometry/Soldermask Bottom")
		(17 "Dwgs.User" user "User.Drawings")
		(19 "Cmts.User" user "User.Comments")
		(21 "Eco1.User" user "User.Eco1")
		(23 "Eco2.User" user "User.Eco2")
		(25 "Edge.Cuts" user "Board Geometry/Outline")
		(27 "Margin" user)
		(31 "F.CrtYd" user "Package Geometry/Place Bound Top")
		(29 "B.CrtYd" user "Package Geometry/Place Bound Bottom")
		(35 "F.Fab" user "Ref Des/Assembly Top")
		(33 "B.Fab" user "Ref Des/Assembly Bottom")
	)
	(footprint ""
		(layer "F.Cu")
		(at 13.462 -50.927 90)
		(property "Reference" "C1E17"
			(at 0 0 90)
			(layer "F.SilkS")
			(hide yes)
			(effects
				(font
					(size 1.27 1.27)
				)
			)
		)
		(property "Value" ""
			(at 0 0 90)
			(layer "F.Fab")
			(effects
				(font
					(size 1.27 1.27)
				)
			)
		)
		(duplicate_pad_numbers_are_jumpers no)
		(fp_rect
			(start -0.3048 -0.1016)
			(end 0.3048 0.9906)
			(stroke
				(width 0)
				(type default)
			)
			(fill no)
			(layer "F.CrtYd")
		)
		(fp_line
			(start 0.3048 -0.1016)
			(end -0.3048 -0.1016)
			(stroke
				(width 0.1)
				(type default)
			)
			(layer "F.Fab")
		)
		(fp_line
			(start -0.3048 -0.1016)
			(end -0.3048 0.9906)
			(stroke
				(width 0.1)
				(type default)
			)
			(layer "F.Fab")
		)
		(fp_line
			(start 0.3048 0.9906)
			(end 0.3048 -0.1016)
			(stroke
				(width 0.1)
				(type default)
			)
			(layer "F.Fab")
		)
		(fp_line
			(start -0.3048 0.9906)
			(end 0.3048 0.9906)
			(stroke
				(width 0.1)
				(type default)
			)
			(layer "F.Fab")
		)
		(pad "1" smd rect
			(at 0 0 90)
			(size 0.508 0.508)
			(layers "F.Cu" "F.Mask" "F.Paste")
			(net "P12V_PSU")
		)
		(pad "2" smd rect
			(at 0 0.889 90)
			(size 0.508 0.508)
			(layers "F.Cu" "F.Mask" "F.Paste")
			(net "GND")
		)
		(zone
			(layer "F.Cu")
			(hatch none 0.5)
			(connect_pads
				(clearance 0)
			)
			(min_thickness 0.25)
			(keepout
				(tracks allowed)
				(vias not_allowed)
				(pads allowed)
				(copperpour not_allowed)
				(footprints allowed)
			)
			(placement
				(enabled no)
				(sheetname "")
			)
			(fill
				(thermal_gap 0.5)
				(thermal_bridge_width 0.5)
				(island_removal_mode 0)
			)
			(polygon
				(pts
					(xy 13.716 -50.673) (xy 14.097 -50.673) (xy 14.097 -51.181) (xy 13.716 -51.181)
				)
			)
		)
		(zone
			(layer "F.Cu")
			(hatch none 0.5)
			(connect_pads
				(clearance 0)
			)
			(min_thickness 0.25)
			(keepout
				(tracks not_allowed)
				(vias allowed)
				(pads allowed)
				(copperpour not_allowed)
				(footprints allowed)
			)
			(placement
				(enabled no)
				(sheetname "")
			)
			(fill
				(thermal_gap 0.5)
				(thermal_bridge_width 0.5)
				(island_removal_mode 0)
			)
			(polygon
				(pts
					(xy 13.716 -50.673) (xy 14.097 -50.673) (xy 14.097 -51.181) (xy 13.716 -51.181)
				)
			)
		)
	)
	(footprint ""
		(layer "F.Cu")
		(at 19.195288 -4.574032 -90)
		(property "Reference" "C1G17"
			(at 0 0 270)
			(layer "F.SilkS")
			(hide yes)
			(effects
				(font
					(size 1.27 1.27)
				)
			)
		)
		(property "Value" ""
			(at 0 0 270)
			(layer "F.Fab")
			(effects
				(font
					(size 1.27 1.27)
				)
			)
		)
		(duplicate_pad_numbers_are_jumpers no)
		(fp_poly
			(pts
				(xy -0.7239 -0.2159) (xy 0.7239 -0.2159) (xy 0.7239 1.9939) (xy -0.7239 1.9939)
			)
			(stroke
				(width 0)
				(type default)
			)
			(fill no)
			(layer "F.CrtYd")
		)
		(fp_line
			(start -0.7239 1.9939)
			(end 0.7239 1.9939)
			(stroke
				(width 0.1)
				(type default)
			)
			(layer "F.Fab")
		)
		(fp_line
			(start 0.7239 1.9939)
			(end 0.7239 -0.2159)
			(stroke
				(width 0.1)
				(type default)
			)
			(layer "F.Fab")
		)
		(fp_line
			(start -0.7239 -0.2159)
			(end -0.7239 1.9939)
			(stroke
				(width 0.1)
				(type default)
			)
			(layer "F.Fab")
		)
		(fp_line
			(start 0.7239 -0.2159)
			(end -0.7239 -0.2159)
			(stroke
				(width 0.1)
				(type default)
			)
			(layer "F.Fab")
		)
		(pad "1" smd rect
			(at 0 0 270)
			(size 1.27 1.016)
			(layers "F.Cu" "F.Mask" "F.Paste")
			(net "PVDDQ_GHJ")
		)
		(pad "2" smd rect
			(at 0 1.778 270)
			(size 1.27 1.016)
			(layers "F.Cu" "F.Mask" "F.Paste")
			(net "GND")
		)
		(zone
			(layer "F.Cu")
			(hatch none 0.5)
			(connect_pads
				(clearance 0)
			)
			(min_thickness 0.25)
			(keepout
				(tracks not_allowed)
				(vias allowed)
				(pads allowed)
				(copperpour not_allowed)
				(footprints allowed)
			)
			(placement
				(enabled no)
				(sheetname "")
			)
			(fill
				(thermal_gap 0.5)
				(thermal_bridge_width 0.5)
				(island_removal_mode 0)
			)
			(polygon
				(pts
					(xy 18.687288 -5.209032) (xy 18.687288 -3.939032) (xy 17.925288 -3.939032) (xy 17.925288 -5.209032)
				)
			)
		)
	)
	(footprint ""
		(layer "F.Cu")
		(at 7.238746 -109.65307 90)
		(property "Reference" "C9M4"
			(at 0 0 90)
			(layer "F.SilkS")
			(hide yes)
			(effects
				(font
					(size 1.27 1.27)
				)
			)
		)
		(property "Value" ""
			(at 0 0 90)
			(layer "F.Fab")
			(effects
				(font
					(size 1.27 1.27)
				)
			)
		)
		(duplicate_pad_numbers_are_jumpers no)
		(fp_poly
			(pts
				(xy -0.7239 -0.2159) (xy 0.7239 -0.2159) (xy 0.7239 1.9939) (xy -0.7239 1.9939)
			)
			(stroke
				(width 0)
				(type default)
			)
			(fill no)
			(layer "F.CrtYd")
		)
		(fp_line
			(start 0.7239 -0.2159)
			(end -0.7239 -0.2159)
			(stroke
				(width 0.1)
				(type default)
			)
			(layer "F.Fab")
		)
		(fp_line
			(start -0.7239 -0.2159)
			(end -0.7239 1.9939)
			(stroke
				(width 0.1)
				(type default)
			)
			(layer "F.Fab")
		)
		(fp_line
			(start 0.7239 1.9939)
			(end 0.7239 -0.2159)
			(stroke
				(width 0.1)
				(type default)
			)
			(layer "F.Fab")
		)
		(fp_line
			(start -0.7239 1.9939)
			(end 0.7239 1.9939)
			(stroke
				(width 0.1)
				(type default)
			)
			(layer "F.Fab")
		)
		(pad "1" smd rect
			(at 0 0 90)
			(size 1.27 1.016)
			(layers "F.Cu" "F.Mask" "F.Paste")
			(net "P12V_FAN")
		)
		(pad "2" smd rect
			(at 0 1.778 90)
			(size 1.27 1.016)
			(layers "F.Cu" "F.Mask" "F.Paste")
			(net "GND")
		)
		(zone
			(layer "F.Cu")
			(hatch none 0.5)
			(connect_pads
				(clearance 0)
			)
			(min_thickness 0.25)
			(keepout
				(tracks not_allowed)
				(vias allowed)
				(pads allowed)
				(copperpour not_allowed)
				(footprints allowed)
			)
			(placement
				(enabled no)
				(sheetname "")
			)
			(fill
				(thermal_gap 0.5)
				(thermal_bridge_width 0.5)
				(island_removal_mode 0)
			)
			(polygon
				(pts
					(xy 7.746746 -109.01807) (xy 7.746746 -110.28807) (xy 8.508746 -110.28807) (xy 8.508746 -109.01807)
				)
			)
		)
	)
)
